(kicad_pcb
	(version 20241229)
	(generator "pcbnew")
	(generator_version "9.0")
	(general
		(thickness 1.6)
		(legacy_teardrops no)
	)
	(paper "A4")
	(title_block
		(title "OCuLink to PCIe adapter")
		(date "2025-06-18")
		(rev "1.0.0")
		(company "Antmicro Ltd")
		(comment 1 "www.antmicro.com")
		(comment 9 "footprints 29-32 of 159")
	)
	(layers
		(0 "F.Cu" signal)
		(4 "In1.Cu" signal)
		(6 "In2.Cu" signal)
		(2 "B.Cu" signal)
		(9 "F.Adhes" user "F.Adhesive")
		(11 "B.Adhes" user "B.Adhesive")
		(13 "F.Paste" user)
		(15 "B.Paste" user)
		(5 "F.SilkS" user "F.Silkscreen")
		(7 "B.SilkS" user "B.Silkscreen")
		(1 "F.Mask" user)
		(3 "B.Mask" user)
		(17 "Dwgs.User" user "User.Drawings")
		(19 "Cmts.User" user "User.Comments")
		(21 "Eco1.User" user "User.Eco1")
		(23 "Eco2.User" user "User.Eco2")
		(25 "Edge.Cuts" user)
		(27 "Margin" user)
		(31 "F.CrtYd" user "F.Courtyard")
		(29 "B.CrtYd" user "B.Courtyard")
		(35 "F.Fab" user)
		(33 "B.Fab" user)
	)
	(footprint "antmicro-footprints:Vishay_PowerPAK_1212-8_Single"
		(layer "F.Cu")
		(at 132.25 104 90)
		(descr "PowerPAK 1212-8 Single")
		(tags "Vishay PowerPAK 1212-8 Single")
		(property "Reference" "Q5"
			(at 1.2 -3.45 180)
			(layer "F.SilkS")
			(effects
				(font
					(size 0.7 0.7)
					(thickness 0.15)
				)
				(justify left bottom)
			)
		)
		(property "Value" "SQS401EN-T1_BE3"
			(at 0 2.7 90)
			(layer "F.Fab")
			(effects
				(font
					(size 0.7 0.7)
					(thickness 0.15)
				)
				(justify left bottom)
			)
		)
		(property "Datasheet" "https://www.vishay.com/docs/65529/sqs401en.pdf"
			(at 0 0 90)
			(layer "F.Fab")
			(hide yes)
			(effects
				(font
					(size 1.27 1.27)
					(thickness 0.15)
				)
			)
		)
		(property "Description" "MOSFET, P Channel, 40 V, 16A, 0.047 ohm, PowerPAK 1212-8, Surface Mount"
			(at 0 0 90)
			(layer "F.Fab")
			(hide yes)
			(effects
				(font
					(size 1.27 1.27)
					(thickness 0.15)
				)
			)
		)
		(property "MPN" "SQS401EN-T1_BE3"
			(at 0 0 90)
			(unlocked yes)
			(layer "F.Fab")
			(hide yes)
			(effects
				(font
					(size 1 1)
					(thickness 0.15)
				)
			)
		)
		(property "Manufacturer" "Vishay"
			(at 0 0 90)
			(unlocked yes)
			(layer "F.Fab")
			(hide yes)
			(effects
				(font
					(size 1 1)
					(thickness 0.15)
				)
			)
		)
		(property "Author" "Antmicro"
			(at 0 0 90)
			(unlocked yes)
			(layer "F.Fab")
			(hide yes)
			(effects
				(font
					(size 1 1)
					(thickness 0.15)
				)
			)
		)
		(property "License" "Apache-2.0"
			(at 0 0 90)
			(unlocked yes)
			(layer "F.Fab")
			(hide yes)
			(effects
				(font
					(size 1 1)
					(thickness 0.15)
				)
			)
		)
		(sheetname "/Power/Ideal-diode-0/")
		(sheetfile "ideal-diode.kicad_sch")
		(attr smd)
		(fp_line
			(start 1.648 -1.651)
			(end 1.648 -1.317)
			(stroke
				(width 0.15)
				(type solid)
			)
			(layer "F.SilkS")
		)
		(fp_line
			(start -1.651 -1.651)
			(end 1.648 -1.651)
			(stroke
				(width 0.15)
				(type solid)
			)
			(layer "F.SilkS")
		)
		(fp_line
			(start -1.651 -1.651)
			(end -1.651 -1.317)
			(stroke
				(width 0.15)
				(type solid)
			)
			(layer "F.SilkS")
		)
		(fp_line
			(start 1.634 1.3)
			(end 1.634 1.634)
			(stroke
				(width 0.15)
				(type solid)
			)
			(layer "F.SilkS")
		)
		(fp_line
			(start -1.635 1.3)
			(end -1.635 1.634)
			(stroke
				(width 0.15)
				(type solid)
			)
			(layer "F.SilkS")
		)
		(fp_line
			(start -1.635 1.634)
			(end 1.634 1.634)
			(stroke
				(width 0.15)
				(type solid)
			)
			(layer "F.SilkS")
		)
		(fp_circle
			(center -1.9 -1.4)
			(end -1.85 -1.4)
			(stroke
				(width 0.15)
				(type solid)
			)
			(fill yes)
			(layer "F.SilkS")
		)
		(fp_rect
			(start -2 -1.8)
			(end 2 1.798)
			(stroke
				(width 0.05)
				(type solid)
			)
			(fill no)
			(layer "F.CrtYd")
		)
		(fp_line
			(start -1.6425 -1.4175)
			(end -1.4175 -1.6425)
			(stroke
				(width 0.15)
				(type solid)
			)
			(layer "F.Fab")
		)
		(fp_rect
			(start -1.651 -1.651)
			(end 1.648 1.648)
			(stroke
				(width 0.15)
				(type solid)
			)
			(fill no)
			(layer "F.Fab")
		)
		(fp_text user "${REFERENCE}"
			(at 0 -0.001 90)
			(layer "F.Fab")
			(effects
				(font
					(size 0.7 0.7)
					(thickness 0.15)
				)
				(justify left bottom)
			)
		)
		(fp_text user "License: Apache-2.0"
			(at -8 7.1 90)
			(layer "F.Fab")
			(effects
				(font
					(size 0.7 0.7)
					(thickness 0.15)
				)
				(justify left bottom)
			)
		)
		(fp_text user "Author: Antmicro"
			(at -8 5.9 90)
			(layer "F.Fab")
			(effects
				(font
					(size 0.7 0.7)
					(thickness 0.15)
				)
				(justify left bottom)
			)
		)
		(pad "1" smd rect
			(at -1.436 -0.99 90)
			(size 0.99 0.405)
			(layers "F.Cu" "F.Mask" "F.Paste")
			(net 87 "+12V")
			(pinfunction "S")
			(pintype "passive")
		)
		(pad "2" smd rect
			(at -1.436 -0.332 90)
			(size 0.99 0.405)
			(layers "F.Cu" "F.Mask" "F.Paste")
			(net 87 "+12V")
			(pinfunction "S")
			(pintype "passive")
		)
		(pad "3" smd rect
			(at -1.436 0.33 90)
			(size 0.99 0.405)
			(layers "F.Cu" "F.Mask" "F.Paste")
			(net 87 "+12V")
			(pinfunction "S")
			(pintype "passive")
		)
		(pad "4" smd rect
			(at -1.436 0.988 90)
			(size 0.99 0.405)
			(layers "F.Cu" "F.Mask" "F.Paste")
			(net 151 "Net-(Q5-G)")
			(pinfunction "G")
			(pintype "input")
		)
		(pad "5" smd custom
			(at 0.557 0 90)
			(size 1.725 2.235)
			(layers "F.Cu" "F.Mask" "F.Paste")
			(net 119 "/Power/VCC_PD")
			(pinfunction "D")
			(pintype "passive")
			(zone_connect 2)
			(options
				(clearance outline)
				(anchor rect)
			)
			(primitives
				(gr_poly
					(pts
						(xy 0.8625 0.1275) (xy 0.8625 -0.1275) (xy 1.3725 -0.1275) (xy 1.3725 -0.5325) (xy 0.8625 -0.5325)
						(xy 0.8625 -0.7875) (xy 1.3725 -0.7875) (xy 1.3725 -1.195) (xy 0.6125 -1.195) (xy 0.6125 1.195)
						(xy 1.3725 1.195) (xy 1.3725 0.7875) (xy 0.8625 0.7875) (xy 0.8625 0.5325) (xy 1.3725 0.5325)
						(xy 1.3725 0.1275)
					)
					(width 0)
					(fill yes)
				)
			)
		)
	)
	(footprint "antmicro-footprints:C_0805_2012Metric"
		(layer "F.Cu")
		(at 119.8 114.2)
		(descr "Capacitor SMD 0805")
		(tags "capacitor SMD 0805")
		(property "Reference" "C36"
			(at -0.4 -1.2 180)
			(layer "F.SilkS")
			(effects
				(font
					(size 0.7 0.7)
					(thickness 0.15)
				)
				(justify left bottom)
			)
		)
		(property "Value" "C_10u_0805_35V"
			(at -2.055717 1.963153 0)
			(layer "F.Fab")
			(effects
				(font
					(size 0.7 0.7)
					(thickness 0.15)
				)
				(justify left bottom)
			)
		)
		(property "Datasheet" "https://www.murata.com/products/productdetail?partno=GRM21BR6YA106KE43%23"
			(at 0 0 0)
			(layer "F.Fab")
			(hide yes)
			(effects
				(font
					(size 1.27 1.27)
					(thickness 0.15)
				)
			)
		)
		(property "Description" "SMD Multilayer Ceramic Capacitor, 10 µF, 35 V, 0805 [2012 Metric], ± 10%, X5R, GRM Series"
			(at 0 0 0)
			(layer "F.Fab")
			(hide yes)
			(effects
				(font
					(size 1.27 1.27)
					(thickness 0.15)
				)
			)
		)
		(property "MPN" "GRM21BR6YA106KE43L"
			(at 0 0 0)
			(unlocked yes)
			(layer "F.Fab")
			(hide yes)
			(effects
				(font
					(size 1 1)
					(thickness 0.15)
				)
			)
		)
		(property "Manufacturer" "Murata"
			(at 0 0 0)
			(unlocked yes)
			(layer "F.Fab")
			(hide yes)
			(effects
				(font
					(size 1 1)
					(thickness 0.15)
				)
			)
		)
		(property "License" "Apache-2.0"
			(at 0 0 0)
			(unlocked yes)
			(layer "F.Fab")
			(hide yes)
			(effects
				(font
					(size 1 1)
					(thickness 0.15)
				)
			)
		)
		(property "Author" "Antmicro"
			(at 0 0 0)
			(unlocked yes)
			(layer "F.Fab")
			(hide yes)
			(effects
				(font
					(size 1 1)
					(thickness 0.15)
				)
			)
		)
		(property "Val" "10u"
			(at 0 0 0)
			(unlocked yes)
			(layer "F.Fab")
			(hide yes)
			(effects
				(font
					(size 1 1)
					(thickness 0.15)
				)
			)
		)
		(property "Voltage" "35V"
			(at 0 0 0)
			(unlocked yes)
			(layer "F.Fab")
			(hide yes)
			(effects
				(font
					(size 1 1)
					(thickness 0.15)
				)
			)
		)
		(property "Dielectric" ""
			(at 0 0 0)
			(unlocked yes)
			(layer "F.Fab")
			(hide yes)
			(effects
				(font
					(size 1 1)
					(thickness 0.15)
				)
			)
		)
		(property "Public" "False"
			(at 0 0 0)
			(unlocked yes)
			(layer "F.Fab")
			(hide yes)
			(effects
				(font
					(size 1 1)
					(thickness 0.15)
				)
			)
		)
		(sheetname "/PCIe-connector/")
		(sheetfile "pcie-connector.kicad_sch")
		(attr smd)
		(fp_line
			(start -0.3 -0.7)
			(end 0.3 -0.7)
			(stroke
				(width 0.15)
				(type solid)
			)
			(layer "F.SilkS")
		)
		(fp_line
			(start -0.3 0.7)
			(end 0.3 0.7)
			(stroke
				(width 0.15)
				(type solid)
			)
			(layer "F.SilkS")
		)
		(fp_rect
			(start 1.95 -0.9)
			(end -1.95 0.9)
			(stroke
				(width 0.05)
				(type default)
			)
			(fill no)
			(layer "F.CrtYd")
		)
		(fp_rect
			(start -0.95 -0.675)
			(end 0.95 0.675)
			(stroke
				(width 0.15)
				(type solid)
			)
			(fill no)
			(layer "F.Fab")
		)
		(fp_text user "License: Apache-2.0"
			(at -1.9 4.947 0)
			(layer "F.Fab")
			(effects
				(font
					(size 0.7 0.7)
					(thickness 0.15)
				)
				(justify left bottom)
			)
		)
		(fp_text user "${REFERENCE}"
			(at 0 0 0)
			(layer "F.Fab")
			(effects
				(font
					(size 0.7 0.7)
					(thickness 0.15)
				)
				(justify left bottom)
			)
		)
		(fp_text user "Author: Antmicro"
			(at -1.9 5.947 0)
			(layer "F.Fab")
			(effects
				(font
					(size 0.7 0.7)
					(thickness 0.15)
				)
				(justify left bottom)
			)
		)
		(pad "1" smd roundrect
			(at -1.1 0)
			(size 1.2 1.3)
			(layers "F.Cu" "F.Mask" "F.Paste")
			(roundrect_rratio 0.25)
			(net 134 "+3V3")
			(pintype "passive")
		)
		(pad "2" smd roundrect
			(at 1.1 0)
			(size 1.2 1.3)
			(layers "F.Cu" "F.Mask" "F.Paste")
			(roundrect_rratio 0.25)
			(net 66 "GND")
			(pintype "passive")
		)
	)
	(footprint "antmicro-footprints:C_0402_1005Metric"
		(layer "F.Cu")
		(at 143.5 120.402999 -90)
		(descr "Capacitor SMD 0402")
		(tags "capacitor SMD 0402")
		(property "Reference" "C34"
			(at -1.002999 -0.8 90)
			(layer "F.SilkS")
			(effects
				(font
					(size 0.7 0.7)
					(thickness 0.15)
				)
				(justify right top)
			)
		)
		(property "Value" "C_100n_0402"
			(at -1.022927 2.155213 90)
			(layer "F.Fab")
			(effects
				(font
					(size 0.7 0.7)
					(thickness 0.15)
				)
				(justify right top)
			)
		)
		(property "Datasheet" "https://www.murata.com/products/productdetail?partno=GRM155R61H104KE14%23"
			(at 0 0 90)
			(layer "F.Fab")
			(hide yes)
			(effects
				(font
					(size 1.27 1.27)
					(thickness 0.15)
				)
			)
		)
		(property "Description" "SMD Multilayer Ceramic Capacitor, 0.1 µF, 50 V, 0402 [1005 Metric], ± 10%, X5R, GRM Series"
			(at 0 0 90)
			(layer "F.Fab")
			(hide yes)
			(effects
				(font
					(size 1.27 1.27)
					(thickness 0.15)
				)
			)
		)
		(property "MPN" "GRM155R61H104KE14D"
			(at 0 0 270)
			(unlocked yes)
			(layer "F.Fab")
			(hide yes)
			(effects
				(font
					(size 1 1)
					(thickness 0.15)
				)
			)
		)
		(property "Manufacturer" "Murata"
			(at 0 0 270)
			(unlocked yes)
			(layer "F.Fab")
			(hide yes)
			(effects
				(font
					(size 1 1)
					(thickness 0.15)
				)
			)
		)
		(property "License" "Apache-2.0"
			(at 0 0 270)
			(unlocked yes)
			(layer "F.Fab")
			(hide yes)
			(effects
				(font
					(size 1 1)
					(thickness 0.15)
				)
			)
		)
		(property "Author" "Antmicro"
			(at 0 0 270)
			(unlocked yes)
			(layer "F.Fab")
			(hide yes)
			(effects
				(font
					(size 1 1)
					(thickness 0.15)
				)
			)
		)
		(property "Val" "100n"
			(at 0 0 270)
			(unlocked yes)
			(layer "F.Fab")
			(hide yes)
			(effects
				(font
					(size 1 1)
					(thickness 0.15)
				)
			)
		)
		(property "Voltage" "50V"
			(at 0 0 270)
			(unlocked yes)
			(layer "F.Fab")
			(hide yes)
			(effects
				(font
					(size 1 1)
					(thickness 0.15)
				)
			)
		)
		(property "Dielectric" "X5R"
			(at 0 0 270)
			(unlocked yes)
			(layer "F.Fab")
			(hide yes)
			(effects
				(font
					(size 1 1)
					(thickness 0.15)
				)
			)
		)
		(sheetname "/Power/Ideal-diode-1/")
		(sheetfile "ideal-diode.kicad_sch")
		(attr smd)
		(fp_rect
			(start -0.925 -0.47)
			(end 0.925 0.47)
			(stroke
				(width 0.05)
				(type default)
			)
			(fill no)
			(layer "F.CrtYd")
		)
		(fp_line
			(start -0.494 0.248)
			(end -0.494 -0.25)
			(stroke
				(width 0.15)
				(type solid)
			)
			(layer "F.Fab")
		)
		(fp_line
			(start 0.504 0.248)
			(end -0.494 0.248)
			(stroke
				(width 0.15)
				(type solid)
			)
			(layer "F.Fab")
		)
		(fp_line
			(start -0.494 -0.25)
			(end 0.504 -0.25)
			(stroke
				(width 0.15)
				(type solid)
			)
			(layer "F.Fab")
		)
		(fp_line
			(start 0.504 -0.25)
			(end 0.504 0.248)
			(stroke
				(width 0.15)
				(type solid)
			)
			(layer "F.Fab")
		)
		(fp_text user "Author: Antmicro"
			(at -0.939 3.399 90)
			(layer "F.Fab")
			(effects
				(font
					(size 0.7 0.7)
					(thickness 0.15)
				)
				(justify right top)
			)
		)
		(fp_text user "${REFERENCE}"
			(at 0 0 90)
			(layer "F.Fab")
			(effects
				(font
					(size 0.7 0.7)
					(thickness 0.15)
				)
				(justify right top)
			)
		)
		(fp_text user "License: Apache-2.0"
			(at -0.939 5.799 90)
			(layer "F.Fab")
			(effects
				(font
					(size 0.7 0.7)
					(thickness 0.15)
				)
				(justify right top)
			)
		)
		(pad "1" smd roundrect
			(at -0.48 0 270)
			(size 0.59 0.64)
			(layers "F.Cu" "F.Mask" "F.Paste")
			(roundrect_rratio 0.25)
			(net 66 "GND")
			(pintype "passive")
		)
		(pad "2" smd roundrect
			(at 0.48 0 270)
			(size 0.59 0.64)
			(layers "F.Cu" "F.Mask" "F.Paste")
			(roundrect_rratio 0.25)
			(net 118 "/Power/Ideal-diode-1/VIN")
			(pintype "passive")
		)
	)
	(footprint "antmicro-footprints:C_0805_2012Metric"
		(layer "F.Cu")
		(at 136.35 89.499998 90)
		(descr "Capacitor SMD 0805")
		(tags "capacitor SMD 0805")
		(property "Reference" "C24"
			(at 0.299998 -3.95 90)
			(layer "F.SilkS")
			(effects
				(font
					(size 0.7 0.7)
					(thickness 0.15)
				)
				(justify left bottom)
			)
		)
		(property "Value" "C_10u_0805_35V"
			(at -2.055717 1.963153 90)
			(layer "F.Fab")
			(effects
				(font
					(size 0.7 0.7)
					(thickness 0.15)
				)
				(justify left bottom)
			)
		)
		(property "Datasheet" "https://www.murata.com/products/productdetail?partno=GRM21BR6YA106KE43%23"
			(at 0 0 90)
			(layer "F.Fab")
			(hide yes)
			(effects
				(font
					(size 1.27 1.27)
					(thickness 0.15)
				)
			)
		)
		(property "Description" "SMD Multilayer Ceramic Capacitor, 10 µF, 35 V, 0805 [2012 Metric], ± 10%, X5R, GRM Series"
			(at 0 0 90)
			(layer "F.Fab")
			(hide yes)
			(effects
				(font
					(size 1.27 1.27)
					(thickness 0.15)
				)
			)
		)
		(property "MPN" "GRM21BR6YA106KE43L"
			(at 0 0 90)
			(unlocked yes)
			(layer "F.Fab")
			(hide yes)
			(effects
				(font
					(size 1 1)
					(thickness 0.15)
				)
			)
		)
		(property "Manufacturer" "Murata"
			(at 0 0 90)
			(unlocked yes)
			(layer "F.Fab")
			(hide yes)
			(effects
				(font
					(size 1 1)
					(thickness 0.15)
				)
			)
		)
		(property "License" "Apache-2.0"
			(at 0 0 90)
			(unlocked yes)
			(layer "F.Fab")
			(hide yes)
			(effects
				(font
					(size 1 1)
					(thickness 0.15)
				)
			)
		)
		(property "Author" "Antmicro"
			(at 0 0 90)
			(unlocked yes)
			(layer "F.Fab")
			(hide yes)
			(effects
				(font
					(size 1 1)
					(thickness 0.15)
				)
			)
		)
		(property "Val" "10u"
			(at 0 0 90)
			(unlocked yes)
			(layer "F.Fab")
			(hide yes)
			(effects
				(font
					(size 1 1)
					(thickness 0.15)
				)
			)
		)
		(property "Voltage" "35V"
			(at 0 0 90)
			(unlocked yes)
			(layer "F.Fab")
			(hide yes)
			(effects
				(font
					(size 1 1)
					(thickness 0.15)
				)
			)
		)
		(property "Dielectric" ""
			(at 0 0 90)
			(unlocked yes)
			(layer "F.Fab")
			(hide yes)
			(effects
				(font
					(size 1 1)
					(thickness 0.15)
				)
			)
		)
		(property "Public" "False"
			(at 0 0 90)
			(unlocked yes)
			(layer "F.Fab")
			(hide yes)
			(effects
				(font
					(size 1 1)
					(thickness 0.15)
				)
			)
		)
		(sheetname "/USB-PD/")
		(sheetfile "usb-pd.kicad_sch")
		(attr smd)
		(fp_line
			(start -0.3 -0.7)
			(end 0.3 -0.7)
			(stroke
				(width 0.15)
				(type solid)
			)
			(layer "F.SilkS")
		)
		(fp_line
			(start -0.3 0.7)
			(end 0.3 0.7)
			(stroke
				(width 0.15)
				(type solid)
			)
			(layer "F.SilkS")
		)
		(fp_rect
			(start 1.95 -0.9)
			(end -1.95 0.9)
			(stroke
				(width 0.05)
				(type default)
			)
			(fill no)
			(layer "F.CrtYd")
		)
		(fp_rect
			(start -0.95 -0.675)
			(end 0.95 0.675)
			(stroke
				(width 0.15)
				(type solid)
			)
			(fill no)
			(layer "F.Fab")
		)
		(fp_text user "Author: Antmicro"
			(at -1.9 5.947 90)
			(layer "F.Fab")
			(effects
				(font
					(size 0.7 0.7)
					(thickness 0.15)
				)
				(justify left bottom)
			)
		)
		(fp_text user "License: Apache-2.0"
			(at -1.9 4.947 90)
			(layer "F.Fab")
			(effects
				(font
					(size 0.7 0.7)
					(thickness 0.15)
				)
				(justify left bottom)
			)
		)
		(fp_text user "${REFERENCE}"
			(at 0 0 90)
			(layer "F.Fab")
			(effects
				(font
					(size 0.7 0.7)
					(thickness 0.15)
				)
				(justify left bottom)
			)
		)
		(pad "1" smd roundrect
			(at -1.1 0 90)
			(size 1.2 1.3)
			(layers "F.Cu" "F.Mask" "F.Paste")
			(roundrect_rratio 0.25)
			(net 66 "GND")
			(pintype "passive")
		)
		(pad "2" smd roundrect
			(at 1.1 0 90)
			(size 1.2 1.3)
			(layers "F.Cu" "F.Mask" "F.Paste")
			(roundrect_rratio 0.25)
			(net 115 "/USB-PD/VCC")
			(pintype "passive")
		)
	)
)
